(kicad_pcb
	(version 20260206)
	(generator "pcbnew")
	(generator_version "10.0")
	(general
		(thickness 1.6)
		(legacy_teardrops no)
	)
	(paper "A4")
	(title_block
		(title "01162023_DA0F0TEBIF0_F0T_Expander_BD_F_brd_V02_OCP.brd")
		(comment 1 "Grand Teton / footprints 7844-7852 of 9728")
	)
	(layers
		(0 "F.Cu" signal "TOP")
		(4 "In1.Cu" signal "GND")
		(6 "In2.Cu" signal "VCC")
		(8 "In3.Cu" signal "VCC1")
		(10 "In4.Cu" signal "GND1")
		(12 "In5.Cu" signal "IN1")
		(14 "In6.Cu" signal "GND2")
		(16 "In7.Cu" signal "IN2")
		(18 "In8.Cu" signal "GND3")
		(20 "In9.Cu" signal "IN3")
		(22 "In10.Cu" signal "GND4")
		(24 "In11.Cu" signal "IN4")
		(26 "In12.Cu" signal "GND5")
		(28 "In13.Cu" signal "IN5")
		(30 "In14.Cu" signal "GND6")
		(32 "In15.Cu" signal "IN6")
		(34 "In16.Cu" signal "GND7")
		(2 "B.Cu" signal "BOTTOM")
		(9 "F.Adhes" user "F.Adhesive")
		(11 "B.Adhes" user "B.Adhesive")
		(13 "F.Paste" user "Package Geometry/Pastemask Top")
		(15 "B.Paste" user "Package Geometry/Pastemask Bottom")
		(5 "F.SilkS" user "Ref Des/Silkscreen Top")
		(7 "B.SilkS" user "Ref Des/Silkscreen Bottom")
		(1 "F.Mask" user "Board Geometry/Soldermask Top")
		(3 "B.Mask" user "Board Geometry/Soldermask Bottom")
		(17 "Dwgs.User" user "User.Drawings")
		(19 "Cmts.User" user "User.Comments")
		(21 "Eco1.User" user "User.Eco1")
		(23 "Eco2.User" user "User.Eco2")
		(25 "Edge.Cuts" user "Board Geometry/Outline")
		(27 "Margin" user)
		(31 "F.CrtYd" user "Package Geometry/Place Bound Top")
		(29 "B.CrtYd" user "Package Geometry/Place Bound Bottom")
		(35 "F.Fab" user "Ref Des/Assembly Top")
		(33 "B.Fab" user "Ref Des/Assembly Bottom")
	)
	(footprint ""
		(layer "B.Cu")
		(at 177.174906 -293.99992 90)
		(property "Reference" "C1396"
			(at 0 0 90)
			(layer "B.SilkS")
			(hide yes)
			(effects
				(font
					(size 1.27 1.27)
				)
				(justify mirror)
			)
		)
		(property "Value" ""
			(at 0 0 90)
			(layer "B.Fab")
			(effects
				(font
					(size 1.27 1.27)
				)
				(justify mirror)
			)
		)
		(duplicate_pad_numbers_are_jumpers no)
		(fp_line
			(start 0.299974 -0.150114)
			(end -0.299974 -0.150114)
			(stroke
				(width 0.1)
				(type default)
			)
			(layer "B.Fab")
		)
		(fp_line
			(start -0.299974 -0.150114)
			(end -0.299974 0.150114)
			(stroke
				(width 0.1)
				(type default)
			)
			(layer "B.Fab")
		)
		(fp_line
			(start 0.299974 0.150114)
			(end 0.299974 -0.150114)
			(stroke
				(width 0.1)
				(type default)
			)
			(layer "B.Fab")
		)
		(fp_line
			(start -0.299974 0.150114)
			(end 0.299974 0.150114)
			(stroke
				(width 0.1)
				(type default)
			)
			(layer "B.Fab")
		)
		(pad "1" smd rect
			(at 0.2667 0 270)
			(size 0.3048 0.381)
			(layers "B.Cu" "B.Mask" "B.Paste")
			(net "P0V8_PEX1")
		)
		(pad "2" smd rect
			(at -0.2667 0 270)
			(size 0.3048 0.381)
			(layers "B.Cu" "B.Mask" "B.Paste")
			(net "GND")
		)
	)
	(footprint ""
		(layer "B.Cu")
		(at 54.899814 -299.699934 -90)
		(property "Reference" "C1220"
			(at 0 0 90)
			(layer "B.SilkS")
			(hide yes)
			(effects
				(font
					(size 1.27 1.27)
				)
				(justify mirror)
			)
		)
		(property "Value" ""
			(at 0 0 90)
			(layer "B.Fab")
			(effects
				(font
					(size 1.27 1.27)
				)
				(justify mirror)
			)
		)
		(duplicate_pad_numbers_are_jumpers no)
		(fp_line
			(start -0.299974 0.150114)
			(end 0.299974 0.150114)
			(stroke
				(width 0.1)
				(type default)
			)
			(layer "B.Fab")
		)
		(fp_line
			(start 0.299974 0.150114)
			(end 0.299974 -0.150114)
			(stroke
				(width 0.1)
				(type default)
			)
			(layer "B.Fab")
		)
		(fp_line
			(start -0.299974 -0.150114)
			(end -0.299974 0.150114)
			(stroke
				(width 0.1)
				(type default)
			)
			(layer "B.Fab")
		)
		(fp_line
			(start 0.299974 -0.150114)
			(end -0.299974 -0.150114)
			(stroke
				(width 0.1)
				(type default)
			)
			(layer "B.Fab")
		)
		(pad "1" smd rect
			(at 0.2667 0 90)
			(size 0.3048 0.381)
			(layers "B.Cu" "B.Mask" "B.Paste")
			(net "P0V8_SERDES_VDDA_PEX0")
		)
		(pad "2" smd rect
			(at -0.2667 0 90)
			(size 0.3048 0.381)
			(layers "B.Cu" "B.Mask" "B.Paste")
			(net "GND")
		)
	)
	(footprint ""
		(layer "B.Cu")
		(at 56.845708 -296.37482)
		(property "Reference" "C1109"
			(at 0 0 0)
			(layer "B.SilkS")
			(hide yes)
			(effects
				(font
					(size 1.27 1.27)
				)
				(justify mirror)
			)
		)
		(property "Value" ""
			(at 0 0 0)
			(layer "B.Fab")
			(effects
				(font
					(size 1.27 1.27)
				)
				(justify mirror)
			)
		)
		(duplicate_pad_numbers_are_jumpers no)
		(fp_line
			(start -0.299974 -0.150114)
			(end -0.299974 0.150114)
			(stroke
				(width 0.1)
				(type default)
			)
			(layer "B.Fab")
		)
		(fp_line
			(start -0.299974 0.150114)
			(end 0.299974 0.150114)
			(stroke
				(width 0.1)
				(type default)
			)
			(layer "B.Fab")
		)
		(fp_line
			(start 0.299974 -0.150114)
			(end -0.299974 -0.150114)
			(stroke
				(width 0.1)
				(type default)
			)
			(layer "B.Fab")
		)
		(fp_line
			(start 0.299974 0.150114)
			(end 0.299974 -0.150114)
			(stroke
				(width 0.1)
				(type default)
			)
			(layer "B.Fab")
		)
		(pad "1" smd rect
			(at 0.2667 0 180)
			(size 0.3048 0.381)
			(layers "B.Cu" "B.Mask" "B.Paste")
			(net "P0V8_PEX0")
		)
		(pad "2" smd rect
			(at -0.2667 0 180)
			(size 0.3048 0.381)
			(layers "B.Cu" "B.Mask" "B.Paste")
			(net "GND")
		)
	)
	(footprint ""
		(layer "B.Cu")
		(at 290.89985 -301.599854 -90)
		(property "Reference" "C1683"
			(at 0 0 90)
			(layer "B.SilkS")
			(hide yes)
			(effects
				(font
					(size 1.27 1.27)
				)
				(justify mirror)
			)
		)
		(property "Value" ""
			(at 0 0 90)
			(layer "B.Fab")
			(effects
				(font
					(size 1.27 1.27)
				)
				(justify mirror)
			)
		)
		(duplicate_pad_numbers_are_jumpers no)
		(fp_line
			(start -0.299974 0.150114)
			(end 0.299974 0.150114)
			(stroke
				(width 0.1)
				(type default)
			)
			(layer "B.Fab")
		)
		(fp_line
			(start 0.299974 0.150114)
			(end 0.299974 -0.150114)
			(stroke
				(width 0.1)
				(type default)
			)
			(layer "B.Fab")
		)
		(fp_line
			(start -0.299974 -0.150114)
			(end -0.299974 0.150114)
			(stroke
				(width 0.1)
				(type default)
			)
			(layer "B.Fab")
		)
		(fp_line
			(start 0.299974 -0.150114)
			(end -0.299974 -0.150114)
			(stroke
				(width 0.1)
				(type default)
			)
			(layer "B.Fab")
		)
		(pad "1" smd rect
			(at 0.2667 0 90)
			(size 0.3048 0.381)
			(layers "B.Cu" "B.Mask" "B.Paste")
			(net "P0V8_SERDES_VDDA_PEX2")
		)
		(pad "2" smd rect
			(at -0.2667 0 90)
			(size 0.3048 0.381)
			(layers "B.Cu" "B.Mask" "B.Paste")
			(net "GND")
		)
	)
	(footprint ""
		(layer "B.Cu")
		(at 290.92017 -296.37482)
		(property "Reference" "C1631"
			(at 0 0 0)
			(layer "B.SilkS")
			(hide yes)
			(effects
				(font
					(size 1.27 1.27)
				)
				(justify mirror)
			)
		)
		(property "Value" ""
			(at 0 0 0)
			(layer "B.Fab")
			(effects
				(font
					(size 1.27 1.27)
				)
				(justify mirror)
			)
		)
		(duplicate_pad_numbers_are_jumpers no)
		(fp_line
			(start -0.299974 -0.150114)
			(end -0.299974 0.150114)
			(stroke
				(width 0.1)
				(type default)
			)
			(layer "B.Fab")
		)
		(fp_line
			(start -0.299974 0.150114)
			(end 0.299974 0.150114)
			(stroke
				(width 0.1)
				(type default)
			)
			(layer "B.Fab")
		)
		(fp_line
			(start 0.299974 -0.150114)
			(end -0.299974 -0.150114)
			(stroke
				(width 0.1)
				(type default)
			)
			(layer "B.Fab")
		)
		(fp_line
			(start 0.299974 0.150114)
			(end 0.299974 -0.150114)
			(stroke
				(width 0.1)
				(type default)
			)
			(layer "B.Fab")
		)
		(pad "1" smd rect
			(at 0.2667 0 180)
			(size 0.3048 0.381)
			(layers "B.Cu" "B.Mask" "B.Paste")
			(net "P0V8_PEX2")
		)
		(pad "2" smd rect
			(at -0.2667 0 180)
			(size 0.3048 0.381)
			(layers "B.Cu" "B.Mask" "B.Paste")
			(net "GND")
		)
	)
	(footprint ""
		(layer "B.Cu")
		(at 117.257322 -325.186294 -90)
		(property "Reference" "C4202"
			(at 0 0 90)
			(layer "B.SilkS")
			(hide yes)
			(effects
				(font
					(size 1.27 1.27)
				)
				(justify mirror)
			)
		)
		(property "Value" ""
			(at 0 0 90)
			(layer "B.Fab")
			(effects
				(font
					(size 1.27 1.27)
				)
				(justify mirror)
			)
		)
		(duplicate_pad_numbers_are_jumpers no)
		(fp_line
			(start -1.2954 0.5842)
			(end 1.2954 0.5842)
			(stroke
				(width 0.1524)
				(type default)
			)
			(layer "B.SilkS")
		)
		(fp_line
			(start 1.2954 0.5842)
			(end 1.2954 -0.5842)
			(stroke
				(width 0.1524)
				(type default)
			)
			(layer "B.SilkS")
		)
		(fp_line
			(start -1.2954 -0.5842)
			(end -1.2954 0.5842)
			(stroke
				(width 0.1524)
				(type default)
			)
			(layer "B.SilkS")
		)
		(fp_line
			(start 1.2954 -0.5842)
			(end -1.2954 -0.5842)
			(stroke
				(width 0.1524)
				(type default)
			)
			(layer "B.SilkS")
		)
		(fp_line
			(start -0.8636 0.4572)
			(end 0.8636 0.4572)
			(stroke
				(width 0.1)
				(type default)
			)
			(layer "B.Fab")
		)
		(fp_line
			(start 0.8636 0.4572)
			(end 0.8636 0.4064)
			(stroke
				(width 0.1)
				(type default)
			)
			(layer "B.Fab")
		)
		(fp_line
			(start -1.1938 0.4064)
			(end -0.8636 0.4064)
			(stroke
				(width 0.1)
				(type default)
			)
			(layer "B.Fab")
		)
		(fp_line
			(start -0.8636 0.4064)
			(end -0.8636 0.4572)
			(stroke
				(width 0.1)
				(type default)
			)
			(layer "B.Fab")
		)
		(fp_line
			(start 0.8636 0.4064)
			(end 1.1938 0.4064)
			(stroke
				(width 0.1)
				(type default)
			)
			(layer "B.Fab")
		)
		(fp_line
			(start 1.1938 0.4064)
			(end 1.1938 -0.4064)
			(stroke
				(width 0.1)
				(type default)
			)
			(layer "B.Fab")
		)
		(fp_line
			(start -1.1938 -0.4064)
			(end -1.1938 0.4064)
			(stroke
				(width 0.1)
				(type default)
			)
			(layer "B.Fab")
		)
		(fp_line
			(start -0.8636 -0.4064)
			(end -1.1938 -0.4064)
			(stroke
				(width 0.1)
				(type default)
			)
			(layer "B.Fab")
		)
		(fp_line
			(start 0.8636 -0.4064)
			(end 0.8636 -0.4572)
			(stroke
				(width 0.1)
				(type default)
			)
			(layer "B.Fab")
		)
		(fp_line
			(start 1.1938 -0.4064)
			(end 0.8636 -0.4064)
			(stroke
				(width 0.1)
				(type default)
			)
			(layer "B.Fab")
		)
		(fp_line
			(start -0.8636 -0.4572)
			(end -0.8636 -0.4064)
			(stroke
				(width 0.1)
				(type default)
			)
			(layer "B.Fab")
		)
		(fp_line
			(start 0.8636 -0.4572)
			(end -0.8636 -0.4572)
			(stroke
				(width 0.1)
				(type default)
			)
			(layer "B.Fab")
		)
		(pad "1" smd rect
			(at 0.7366 0 180)
			(size 0.7112 0.8128)
			(layers "B.Cu" "B.Mask" "B.Paste")
			(net "P0V8_SERDES_VDDA_PEX0_C0")
		)
		(pad "2" smd rect
			(at -0.7366 0 180)
			(size 0.7112 0.8128)
			(layers "B.Cu" "B.Mask" "B.Paste")
			(net "GND")
		)
	)
	(footprint ""
		(layer "B.Cu")
		(at 111.089186 -284.796738 -90)
		(property "Reference" "PC79"
			(at 0 0 90)
			(layer "B.SilkS")
			(hide yes)
			(effects
				(font
					(size 1.27 1.27)
				)
				(justify mirror)
			)
		)
		(property "Value" ""
			(at 0 0 90)
			(layer "B.Fab")
			(effects
				(font
					(size 1.27 1.27)
				)
				(justify mirror)
			)
		)
		(duplicate_pad_numbers_are_jumpers no)
		(fp_line
			(start -1.524 0.762)
			(end 1.524 0.762)
			(stroke
				(width 0.1524)
				(type default)
			)
			(layer "B.SilkS")
		)
		(fp_line
			(start 1.524 0.762)
			(end 1.524 -0.762)
			(stroke
				(width 0.1524)
				(type default)
			)
			(layer "B.SilkS")
		)
		(fp_line
			(start -1.524 -0.762)
			(end -1.524 0.762)
			(stroke
				(width 0.1524)
				(type default)
			)
			(layer "B.SilkS")
		)
		(fp_line
			(start 1.524 -0.762)
			(end -1.524 -0.762)
			(stroke
				(width 0.1524)
				(type default)
			)
			(layer "B.SilkS")
		)
		(fp_line
			(start -1.1049 0.724916)
			(end -1.1049 -0.724916)
			(stroke
				(width 0.1)
				(type default)
			)
			(layer "B.Fab")
		)
		(fp_line
			(start 1.1049 0.724916)
			(end -1.1049 0.724916)
			(stroke
				(width 0.1)
				(type default)
			)
			(layer "B.Fab")
		)
		(fp_line
			(start -1.1049 -0.724916)
			(end 1.1049 -0.724916)
			(stroke
				(width 0.1)
				(type default)
			)
			(layer "B.Fab")
		)
		(fp_line
			(start 1.1049 -0.724916)
			(end 1.1049 0.724916)
			(stroke
				(width 0.1)
				(type default)
			)
			(layer "B.Fab")
		)
		(pad "1" smd rect
			(at 0.889 0 270)
			(size 1.016 1.27)
			(layers "B.Cu" "B.Mask" "B.Paste")
			(net "SW_P12V_P0V8_PEX0_FLT")
		)
		(pad "2" smd rect
			(at -0.889 0 270)
			(size 1.016 1.27)
			(layers "B.Cu" "B.Mask" "B.Paste")
			(net "GND")
		)
	)
	(footprint ""
		(layer "B.Cu")
		(at 405.730202 -295.221914)
		(property "Reference" "C1867"
			(at 0 0 0)
			(layer "B.SilkS")
			(hide yes)
			(effects
				(font
					(size 1.27 1.27)
				)
				(justify mirror)
			)
		)
		(property "Value" ""
			(at 0 0 0)
			(layer "B.Fab")
			(effects
				(font
					(size 1.27 1.27)
				)
				(justify mirror)
			)
		)
		(duplicate_pad_numbers_are_jumpers no)
		(fp_line
			(start -1.2954 -0.5842)
			(end -1.2954 0.5842)
			(stroke
				(width 0.1524)
				(type default)
			)
			(layer "B.SilkS")
		)
		(fp_line
			(start -1.2954 0.5842)
			(end 1.2954 0.5842)
			(stroke
				(width 0.1524)
				(type default)
			)
			(layer "B.SilkS")
		)
		(fp_line
			(start 1.2954 -0.5842)
			(end -1.2954 -0.5842)
			(stroke
				(width 0.1524)
				(type default)
			)
			(layer "B.SilkS")
		)
		(fp_line
			(start 1.2954 0.5842)
			(end 1.2954 -0.5842)
			(stroke
				(width 0.1524)
				(type default)
			)
			(layer "B.SilkS")
		)
		(fp_line
			(start -1.1938 -0.4064)
			(end -1.1938 0.4064)
			(stroke
				(width 0.1)
				(type default)
			)
			(layer "B.Fab")
		)
		(fp_line
			(start -1.1938 0.4064)
			(end -0.8636 0.4064)
			(stroke
				(width 0.1)
				(type default)
			)
			(layer "B.Fab")
		)
		(fp_line
			(start -0.8636 -0.4572)
			(end -0.8636 -0.4064)
			(stroke
				(width 0.1)
				(type default)
			)
			(layer "B.Fab")
		)
		(fp_line
			(start -0.8636 -0.4064)
			(end -1.1938 -0.4064)
			(stroke
				(width 0.1)
				(type default)
			)
			(layer "B.Fab")
		)
		(fp_line
			(start -0.8636 0.4064)
			(end -0.8636 0.4572)
			(stroke
				(width 0.1)
				(type default)
			)
			(layer "B.Fab")
		)
		(fp_line
			(start -0.8636 0.4572)
			(end 0.8636 0.4572)
			(stroke
				(width 0.1)
				(type default)
			)
			(layer "B.Fab")
		)
		(fp_line
			(start 0.8636 -0.4572)
			(end -0.8636 -0.4572)
			(stroke
				(width 0.1)
				(type default)
			)
			(layer "B.Fab")
		)
		(fp_line
			(start 0.8636 -0.4064)
			(end 0.8636 -0.4572)
			(stroke
				(width 0.1)
				(type default)
			)
			(layer "B.Fab")
		)
		(fp_line
			(start 0.8636 0.4064)
			(end 1.1938 0.4064)
			(stroke
				(width 0.1)
				(type default)
			)
			(layer "B.Fab")
		)
		(fp_line
			(start 0.8636 0.4572)
			(end 0.8636 0.4064)
			(stroke
				(width 0.1)
				(type default)
			)
			(layer "B.Fab")
		)
		(fp_line
			(start 1.1938 -0.4064)
			(end 0.8636 -0.4064)
			(stroke
				(width 0.1)
				(type default)
			)
			(layer "B.Fab")
		)
		(fp_line
			(start 1.1938 0.4064)
			(end 1.1938 -0.4064)
			(stroke
				(width 0.1)
				(type default)
			)
			(layer "B.Fab")
		)
		(pad "1" smd rect
			(at 0.7366 0 270)
			(size 0.7112 0.8128)
			(layers "B.Cu" "B.Mask" "B.Paste")
			(net "P0V8_PEX3")
		)
		(pad "2" smd rect
			(at -0.7366 0 270)
			(size 0.7112 0.8128)
			(layers "B.Cu" "B.Mask" "B.Paste")
			(net "GND")
		)
	)
	(footprint ""
		(layer "B.Cu")
		(at 14.312392 -453.121014)
		(property "Reference" "X64"
			(at -0.9017 -2.08407 180)
			(unlocked yes)
			(layer "B.SilkS")
			(effects
				(font
					(size 0.7874 0.5842)
					(thickness 0.1524)
				)
				(justify mirror)
			)
		)
		(property "Value" ""
			(at 0 0 0)
			(layer "B.Fab")
			(effects
				(font
					(size 1.27 1.27)
				)
				(justify mirror)
			)
		)
		(property "User Part Number" "TP15"
			(at -1.30175 1.27 270)
			(unlocked yes)
			(layer "Cmts.User")
			(hide yes)
			(effects
				(font
					(size 0.635 0.4064)
					(thickness 0.1524)
				)
				(justify mirror)
			)
		)
		(property "Device Type" "TP_TDR_4P_FTS_MPKT4_H025P0200_IO_TP15_TP_TDR_4P_DIP"
			(at -1.30175 1.27 270)
			(unlocked yes)
			(layer "B.Fab")
			(hide yes)
			(effects
				(font
					(size 0.635 0.4064)
					(thickness 0.1524)
				)
				(justify mirror)
			)
		)
		(duplicate_pad_numbers_are_jumpers no)
		(fp_line
			(start -2.54 -1.27)
			(end 0 -1.27)
			(stroke
				(width 0.1524)
				(type default)
			)
			(layer "B.SilkS")
		)
		(fp_line
			(start -2.54 -1.1303)
			(end -2.54 -1.27)
			(stroke
				(width 0.1524)
				(type default)
			)
			(layer "B.SilkS")
		)
		(fp_line
			(start -2.54 1.4097)
			(end -2.54 1.1303)
			(stroke
				(width 0.1524)
				(type default)
			)
			(layer "B.SilkS")
		)
		(fp_line
			(start -2.54 3.81)
			(end -2.54 3.6703)
			(stroke
				(width 0.1524)
				(type default)
			)
			(layer "B.SilkS")
		)
		(fp_line
			(start 0 -1.27)
			(end 0 -0.635)
			(stroke
				(width 0.1524)
				(type default)
			)
			(layer "B.SilkS")
		)
		(fp_line
			(start 0 0.635)
			(end 0 1.905)
			(stroke
				(width 0.1524)
				(type default)
			)
			(layer "B.SilkS")
		)
		(fp_line
			(start 0 3.175)
			(end 0 3.81)
			(stroke
				(width 0.1524)
				(type default)
			)
			(layer "B.SilkS")
		)
		(fp_line
			(start 0 3.81)
			(end -2.54 3.81)
			(stroke
				(width 0.1524)
				(type default)
			)
			(layer "B.SilkS")
		)
		(fp_poly
			(pts
				(xy 0.761746 0) (xy 2.285746 -0.762) (xy 2.285746 0.762)
			)
			(stroke
				(width 0)
				(type default)
			)
			(fill yes)
			(layer "B.SilkS")
		)
		(fp_line
			(start -2.54 -1.27)
			(end 0 -1.27)
			(stroke
				(width 0.1)
				(type default)
			)
			(layer "B.Fab")
		)
		(fp_line
			(start -2.54 3.81)
			(end -2.54 -1.27)
			(stroke
				(width 0.1)
				(type default)
			)
			(layer "B.Fab")
		)
		(fp_line
			(start 0 -1.27)
			(end 0 3.81)
			(stroke
				(width 0.1)
				(type default)
			)
			(layer "B.Fab")
		)
		(fp_line
			(start 0 3.81)
			(end -2.54 3.81)
			(stroke
				(width 0.1)
				(type default)
			)
			(layer "B.Fab")
		)
		(fp_poly
			(pts
				(xy 0.761746 0) (xy 2.285746 -0.762) (xy 2.285746 0.762)
			)
			(stroke
				(width 0)
				(type default)
			)
			(fill yes)
			(layer "B.Fab")
		)
		(pad "1" thru_hole circle
			(at 0 0 180)
			(size 1.0033 1.0033)
			(drill 0.249936)
			(layers "*.Cu" "*.Mask")
			(remove_unused_layers no)
			(net "TDR_DIFF_85_IN6_DIP")
			(clearance 0.10795)
			(padstack
				(mode front_inner_back)
				(layer "Inner"
					(shape circle)
					(size 0.8001 0.8001)
					(clearance 0.1524)
				)
				(layer "B.Cu"
					(shape circle)
					(size 1.0033 1.0033)
					(thermal_gap 0.10795)
					(clearance 0.10795)
				)
			)
		)
		(pad "2" thru_hole circle
			(at -2.54 0 180)
			(size 1.9939 1.9939)
			(drill 0.249936)
			(layers "*.Cu" "*.Mask")
			(remove_unused_layers no)
			(net "COUPON_GND1")
			(clearance 0.10795)
			(padstack
				(mode front_inner_back)
				(layer "Inner"
					(shape circle)
					(size 0.8001 0.8001)
					(clearance 0.1524)
				)
				(layer "B.Cu"
					(shape circle)
					(size 1.9939 1.9939)
					(thermal_gap 0.10795)
					(clearance 0.10795)
				)
			)
		)
		(pad "3" thru_hole circle
			(at -2.54 2.54 180)
			(size 1.9939 1.9939)
			(drill 0.249936)
			(layers "*.Cu" "*.Mask")
			(remove_unused_layers no)
			(net "COUPON_GND1")
			(clearance 0.10795)
			(padstack
				(mode front_inner_back)
				(layer "Inner"
					(shape circle)
					(size 0.8001 0.8001)
					(clearance 0.1524)
				)
				(layer "B.Cu"
					(shape circle)
					(size 1.9939 1.9939)
					(thermal_gap 0.10795)
					(clearance 0.10795)
				)
			)
		)
		(pad "4" thru_hole circle
			(at 0 2.54 180)
			(size 1.0033 1.0033)
			(drill 0.249936)
			(layers "*.Cu" "*.Mask")
			(remove_unused_layers no)
			(net "TDR_DIFF_85_IN6_DIN")
			(clearance 0.10795)
			(padstack
				(mode front_inner_back)
				(layer "Inner"
					(shape circle)
					(size 0.8001 0.8001)
					(clearance 0.1524)
				)
				(layer "B.Cu"
					(shape circle)
					(size 1.0033 1.0033)
					(thermal_gap 0.10795)
					(clearance 0.10795)
				)
			)
		)
	)
)
